(kicad_pcb
	(version 20260206)
	(generator "pcbnew")
	(generator_version "10.0")
	(general
		(thickness 1.6)
		(legacy_teardrops no)
	)
	(paper "A4")
	(title_block
		(title "Wiwynn_Tioga_Pass_MB.brd")
		(comment 1 "Tioga Pass / footprints 3782-3789 of 4770")
	)
	(layers
		(0 "F.Cu" signal "TOP")
		(4 "In1.Cu" signal "L2GND")
		(6 "In2.Cu" signal "L3")
		(8 "In3.Cu" signal "L4GND")
		(10 "In4.Cu" signal "L5")
		(12 "In5.Cu" signal "L6GND")
		(14 "In6.Cu" signal "L7VCC")
		(16 "In7.Cu" signal "L8VCC")
		(18 "In8.Cu" signal "L9GND")
		(20 "In9.Cu" signal "L10")
		(22 "In10.Cu" signal "L11GND")
		(24 "In11.Cu" signal "L12")
		(26 "In12.Cu" signal "L13GND")
		(2 "B.Cu" signal "BOTTOM")
		(9 "F.Adhes" user "F.Adhesive")
		(11 "B.Adhes" user "B.Adhesive")
		(13 "F.Paste" user "Package Geometry/Pastemask Top")
		(15 "B.Paste" user "Package Geometry/Pastemask Bottom")
		(5 "F.SilkS" user "Ref Des/Silkscreen Top")
		(7 "B.SilkS" user "Ref Des/Silkscreen Bottom")
		(1 "F.Mask" user "Board Geometry/Soldermask Top")
		(3 "B.Mask" user "Board Geometry/Soldermask Bottom")
		(17 "Dwgs.User" user "User.Drawings")
		(19 "Cmts.User" user "User.Comments")
		(21 "Eco1.User" user "User.Eco1")
		(23 "Eco2.User" user "User.Eco2")
		(25 "Edge.Cuts" user "Board Geometry/Outline")
		(27 "Margin" user)
		(31 "F.CrtYd" user "Package Geometry/Place Bound Top")
		(29 "B.CrtYd" user "Package Geometry/Place Bound Bottom")
		(35 "F.Fab" user "Ref Des/Assembly Top")
		(33 "B.Fab" user "Ref Des/Assembly Bottom")
	)
	(footprint ""
		(layer "B.Cu")
		(at 487.9975 -152.5016 -90)
		(property "Reference" "C1L4"
			(at 0 0 90)
			(layer "B.SilkS")
			(hide yes)
			(effects
				(font
					(size 1.27 1.27)
				)
				(justify mirror)
			)
		)
		(property "Value" ""
			(at 0 0 90)
			(layer "B.Fab")
			(effects
				(font
					(size 1.27 1.27)
				)
				(justify mirror)
			)
		)
		(duplicate_pad_numbers_are_jumpers no)
		(fp_poly
			(pts
				(xy -0.3048 -0.1016) (xy -0.3048 0.9906) (xy 0.3048 0.9906) (xy 0.3048 -0.1016)
			)
			(stroke
				(width 0)
				(type default)
			)
			(fill no)
			(layer "B.CrtYd")
		)
		(fp_line
			(start -0.3048 0.9906)
			(end -0.3048 -0.1016)
			(stroke
				(width 0.1)
				(type default)
			)
			(layer "B.Fab")
		)
		(fp_line
			(start 0.3048 0.9906)
			(end -0.3048 0.9906)
			(stroke
				(width 0.1)
				(type default)
			)
			(layer "B.Fab")
		)
		(fp_line
			(start -0.3048 -0.1016)
			(end 0.3048 -0.1016)
			(stroke
				(width 0.1)
				(type default)
			)
			(layer "B.Fab")
		)
		(fp_line
			(start 0.3048 -0.1016)
			(end 0.3048 0.9906)
			(stroke
				(width 0.1)
				(type default)
			)
			(layer "B.Fab")
		)
		(pad "1" smd rect
			(at 0 0 90)
			(size 0.508 0.508)
			(layers "B.Cu" "B.Mask" "B.Paste")
			(net "P5V_STBY")
		)
		(pad "2" smd rect
			(at 0 0.889 90)
			(size 0.508 0.508)
			(layers "B.Cu" "B.Mask" "B.Paste")
			(net "GND")
		)
		(zone
			(layer "B.Cu")
			(hatch none 0.5)
			(connect_pads
				(clearance 0)
			)
			(min_thickness 0.25)
			(keepout
				(tracks not_allowed)
				(vias allowed)
				(pads allowed)
				(copperpour not_allowed)
				(footprints allowed)
			)
			(placement
				(enabled no)
				(sheetname "")
			)
			(fill
				(thermal_gap 0.5)
				(thermal_bridge_width 0.5)
				(island_removal_mode 0)
			)
			(polygon
				(pts
					(xy 487.3625 -152.2476) (xy 487.3625 -152.7556) (xy 487.7435 -152.7556) (xy 487.7435 -152.2476)
				)
			)
		)
		(zone
			(layer "B.Cu")
			(hatch none 0.5)
			(connect_pads
				(clearance 0)
			)
			(min_thickness 0.25)
			(keepout
				(tracks allowed)
				(vias not_allowed)
				(pads allowed)
				(copperpour not_allowed)
				(footprints allowed)
			)
			(placement
				(enabled no)
				(sheetname "")
			)
			(fill
				(thermal_gap 0.5)
				(thermal_bridge_width 0.5)
				(island_removal_mode 0)
			)
			(polygon
				(pts
					(xy 487.7435 -152.2476) (xy 487.7435 -152.7556) (xy 487.3625 -152.7556) (xy 487.3625 -152.2476)
				)
			)
		)
	)
	(footprint ""
		(layer "B.Cu")
		(at 3.8227 -7.727696 90)
		(property "Reference" "C9U6"
			(at 0 0 90)
			(layer "B.SilkS")
			(hide yes)
			(effects
				(font
					(size 1.27 1.27)
				)
				(justify mirror)
			)
		)
		(property "Value" ""
			(at 0 0 90)
			(layer "B.Fab")
			(effects
				(font
					(size 1.27 1.27)
				)
				(justify mirror)
			)
		)
		(duplicate_pad_numbers_are_jumpers no)
		(fp_rect
			(start -0.7239 -0.2159)
			(end 0.7239 1.9939)
			(stroke
				(width 0)
				(type default)
			)
			(fill no)
			(layer "B.CrtYd")
		)
		(fp_line
			(start 0.7239 -0.2159)
			(end 0.7239 1.9939)
			(stroke
				(width 0.1)
				(type default)
			)
			(layer "B.Fab")
		)
		(fp_line
			(start -0.7239 -0.2159)
			(end 0.7239 -0.2159)
			(stroke
				(width 0.1)
				(type default)
			)
			(layer "B.Fab")
		)
		(fp_line
			(start 0.7239 1.9939)
			(end -0.7239 1.9939)
			(stroke
				(width 0.1)
				(type default)
			)
			(layer "B.Fab")
		)
		(fp_line
			(start -0.7239 1.9939)
			(end -0.7239 -0.2159)
			(stroke
				(width 0.1)
				(type default)
			)
			(layer "B.Fab")
		)
		(pad "1" smd rect
			(at 0 0 270)
			(size 1.27 1.016)
			(layers "B.Cu" "B.Mask" "B.Paste")
			(net "VR_FET_SW_P12V_STBY_PVDDQ_GHJ")
		)
		(pad "2" smd rect
			(at 0 1.778 270)
			(size 1.27 1.016)
			(layers "B.Cu" "B.Mask" "B.Paste")
			(net "GND")
		)
		(zone
			(layer "B.Cu")
			(hatch none 0.5)
			(connect_pads
				(clearance 0)
			)
			(min_thickness 0.25)
			(keepout
				(tracks not_allowed)
				(vias allowed)
				(pads allowed)
				(copperpour not_allowed)
				(footprints allowed)
			)
			(placement
				(enabled no)
				(sheetname "")
			)
			(fill
				(thermal_gap 0.5)
				(thermal_bridge_width 0.5)
				(island_removal_mode 0)
			)
			(polygon
				(pts
					(xy 4.3307 -7.092696) (xy 5.0927 -7.092696) (xy 5.0927 -8.362696) (xy 4.3307 -8.362696)
				)
			)
		)
	)
	(footprint ""
		(layer "B.Cu")
		(at 28.0924 -17.723612 -90)
		(property "Reference" "C9T8"
			(at 0 0 90)
			(layer "B.SilkS")
			(hide yes)
			(effects
				(font
					(size 1.27 1.27)
				)
				(justify mirror)
			)
		)
		(property "Value" ""
			(at 0 0 90)
			(layer "B.Fab")
			(effects
				(font
					(size 1.27 1.27)
				)
				(justify mirror)
			)
		)
		(duplicate_pad_numbers_are_jumpers no)
		(fp_rect
			(start 0.7239 -0.2159)
			(end -0.7239 1.9939)
			(stroke
				(width 0)
				(type default)
			)
			(fill no)
			(layer "B.CrtYd")
		)
		(fp_line
			(start -0.7239 1.9939)
			(end -0.7239 -0.2159)
			(stroke
				(width 0.1)
				(type default)
			)
			(layer "B.Fab")
		)
		(fp_line
			(start 0.7239 1.9939)
			(end -0.7239 1.9939)
			(stroke
				(width 0.1)
				(type default)
			)
			(layer "B.Fab")
		)
		(fp_line
			(start -0.7239 -0.2159)
			(end 0.7239 -0.2159)
			(stroke
				(width 0.1)
				(type default)
			)
			(layer "B.Fab")
		)
		(fp_line
			(start 0.7239 -0.2159)
			(end 0.7239 1.9939)
			(stroke
				(width 0.1)
				(type default)
			)
			(layer "B.Fab")
		)
		(pad "1" smd rect
			(at 0 0 90)
			(size 1.27 1.016)
			(layers "B.Cu" "B.Mask" "B.Paste")
			(net "P12V_NVDIMM_GHJ")
		)
		(pad "2" smd rect
			(at 0 1.778 90)
			(size 1.27 1.016)
			(layers "B.Cu" "B.Mask" "B.Paste")
			(net "GND")
		)
		(zone
			(layer "B.Cu")
			(hatch none 0.5)
			(connect_pads
				(clearance 0)
			)
			(min_thickness 0.25)
			(keepout
				(tracks not_allowed)
				(vias allowed)
				(pads allowed)
				(copperpour not_allowed)
				(footprints allowed)
			)
			(placement
				(enabled no)
				(sheetname "")
			)
			(fill
				(thermal_gap 0.5)
				(thermal_bridge_width 0.5)
				(island_removal_mode 0)
			)
			(polygon
				(pts
					(xy 27.5844 -17.088612) (xy 27.5844 -18.358612) (xy 26.8224 -18.358612) (xy 26.8224 -17.088612)
				)
			)
		)
	)
	(footprint ""
		(layer "B.Cu")
		(at 9.398 -68.0466 180)
		(property "Reference" "R9P27"
			(at 0 0 0)
			(layer "B.SilkS")
			(hide yes)
			(effects
				(font
					(size 1.27 1.27)
				)
				(justify mirror)
			)
		)
		(property "Value" ""
			(at 0 0 0)
			(layer "B.Fab")
			(effects
				(font
					(size 1.27 1.27)
				)
				(justify mirror)
			)
		)
		(duplicate_pad_numbers_are_jumpers no)
		(fp_rect
			(start -0.2794 0.9906)
			(end 0.2794 -0.1016)
			(stroke
				(width 0)
				(type default)
			)
			(fill no)
			(layer "B.CrtYd")
		)
		(fp_line
			(start 0.2794 0.9906)
			(end -0.2794 0.9906)
			(stroke
				(width 0.1)
				(type default)
			)
			(layer "B.Fab")
		)
		(fp_line
			(start 0.2794 -0.1016)
			(end 0.2794 0.9906)
			(stroke
				(width 0.1)
				(type default)
			)
			(layer "B.Fab")
		)
		(fp_line
			(start -0.2794 0.9906)
			(end -0.2794 -0.1016)
			(stroke
				(width 0.1)
				(type default)
			)
			(layer "B.Fab")
		)
		(fp_line
			(start -0.2794 -0.1016)
			(end 0.2794 -0.1016)
			(stroke
				(width 0.1)
				(type default)
			)
			(layer "B.Fab")
		)
		(pad "1" smd rect
			(at 0 0)
			(size 0.508 0.508)
			(layers "B.Cu" "B.Mask" "B.Paste")
			(net "P12V_HSC_SENP1")
		)
		(pad "2" smd rect
			(at 0 0.889)
			(size 0.508 0.508)
			(layers "B.Cu" "B.Mask" "B.Paste")
			(net "A_HSC_HSP")
		)
		(zone
			(layer "B.Cu")
			(hatch none 0.5)
			(connect_pads
				(clearance 0)
			)
			(min_thickness 0.25)
			(keepout
				(tracks allowed)
				(vias not_allowed)
				(pads allowed)
				(copperpour not_allowed)
				(footprints allowed)
			)
			(placement
				(enabled no)
				(sheetname "")
			)
			(fill
				(thermal_gap 0.5)
				(thermal_bridge_width 0.5)
				(island_removal_mode 0)
			)
			(polygon
				(pts
					(xy 9.652 -68.6816) (xy 9.144 -68.6816) (xy 9.144 -68.3006) (xy 9.652 -68.3006)
				)
			)
		)
		(zone
			(layer "B.Cu")
			(hatch none 0.5)
			(connect_pads
				(clearance 0)
			)
			(min_thickness 0.25)
			(keepout
				(tracks not_allowed)
				(vias allowed)
				(pads allowed)
				(copperpour not_allowed)
				(footprints allowed)
			)
			(placement
				(enabled no)
				(sheetname "")
			)
			(fill
				(thermal_gap 0.5)
				(thermal_bridge_width 0.5)
				(island_removal_mode 0)
			)
			(polygon
				(pts
					(xy 9.652 -68.6816) (xy 9.144 -68.6816) (xy 9.144 -68.3006) (xy 9.652 -68.3006)
				)
			)
		)
	)
	(footprint ""
		(layer "B.Cu")
		(at 334.743806 -60.368434)
		(property "Reference" "R2U15"
			(at 0 0 0)
			(layer "B.SilkS")
			(hide yes)
			(effects
				(font
					(size 1.27 1.27)
				)
				(justify mirror)
			)
		)
		(property "Value" ""
			(at 0 0 0)
			(layer "B.Fab")
			(effects
				(font
					(size 1.27 1.27)
				)
				(justify mirror)
			)
		)
		(duplicate_pad_numbers_are_jumpers no)
		(fp_poly
			(pts
				(xy 0.2794 -0.1016) (xy -0.2794 -0.1016) (xy -0.2794 0.9906) (xy 0.2794 0.9906)
			)
			(stroke
				(width 0)
				(type default)
			)
			(fill no)
			(layer "B.CrtYd")
		)
		(fp_line
			(start -0.2794 -0.1016)
			(end 0.2794 -0.1016)
			(stroke
				(width 0.1)
				(type default)
			)
			(layer "B.Fab")
		)
		(fp_line
			(start -0.2794 0.9906)
			(end -0.2794 -0.1016)
			(stroke
				(width 0.1)
				(type default)
			)
			(layer "B.Fab")
		)
		(fp_line
			(start 0.2794 -0.1016)
			(end 0.2794 0.9906)
			(stroke
				(width 0.1)
				(type default)
			)
			(layer "B.Fab")
		)
		(fp_line
			(start 0.2794 0.9906)
			(end -0.2794 0.9906)
			(stroke
				(width 0.1)
				(type default)
			)
			(layer "B.Fab")
		)
		(pad "1" smd rect
			(at 0 0 180)
			(size 0.508 0.508)
			(layers "B.Cu" "B.Mask" "B.Paste")
			(net "P3E_CPU0_PE1_SS_RXN<0>")
		)
		(pad "2" smd rect
			(at 0 0.889 180)
			(size 0.508 0.508)
			(layers "B.Cu" "B.Mask" "B.Paste")
			(net "P3E_CPU0_PE1_SS_R_RXN<0>")
		)
		(zone
			(layer "B.Cu")
			(hatch none 0.5)
			(connect_pads
				(clearance 0)
			)
			(min_thickness 0.25)
			(keepout
				(tracks allowed)
				(vias not_allowed)
				(pads allowed)
				(copperpour not_allowed)
				(footprints allowed)
			)
			(placement
				(enabled no)
				(sheetname "")
			)
			(fill
				(thermal_gap 0.5)
				(thermal_bridge_width 0.5)
				(island_removal_mode 0)
			)
			(polygon
				(pts
					(xy 334.997806 -60.114434) (xy 334.489806 -60.114434) (xy 334.489806 -59.733434) (xy 334.997806 -59.733434)
				)
			)
		)
		(zone
			(layer "B.Cu")
			(hatch none 0.5)
			(connect_pads
				(clearance 0)
			)
			(min_thickness 0.25)
			(keepout
				(tracks not_allowed)
				(vias allowed)
				(pads allowed)
				(copperpour not_allowed)
				(footprints allowed)
			)
			(placement
				(enabled no)
				(sheetname "")
			)
			(fill
				(thermal_gap 0.5)
				(thermal_bridge_width 0.5)
				(island_removal_mode 0)
			)
			(polygon
				(pts
					(xy 334.997806 -59.733434) (xy 334.489806 -59.733434) (xy 334.489806 -60.114434) (xy 334.997806 -60.114434)
				)
			)
		)
	)
	(footprint ""
		(layer "B.Cu")
		(at 476.4151 -37.5412 90)
		(property "Reference" "R1T33"
			(at 0 0 90)
			(layer "B.SilkS")
			(hide yes)
			(effects
				(font
					(size 1.27 1.27)
				)
				(justify mirror)
			)
		)
		(property "Value" ""
			(at 0 0 90)
			(layer "B.Fab")
			(effects
				(font
					(size 1.27 1.27)
				)
				(justify mirror)
			)
		)
		(duplicate_pad_numbers_are_jumpers no)
		(fp_poly
			(pts
				(xy 0.4953 -0.2032) (xy -0.4953 -0.2032) (xy -0.4953 1.6002) (xy 0.4953 1.6002)
			)
			(stroke
				(width 0)
				(type default)
			)
			(fill no)
			(layer "B.CrtYd")
		)
		(fp_line
			(start 0.4953 -0.2032)
			(end -0.4953 -0.2032)
			(stroke
				(width 0.1)
				(type default)
			)
			(layer "B.Fab")
		)
		(fp_line
			(start -0.4953 -0.2032)
			(end -0.4953 1.6002)
			(stroke
				(width 0.1)
				(type default)
			)
			(layer "B.Fab")
		)
		(fp_line
			(start 0.4953 1.6002)
			(end 0.4953 -0.2032)
			(stroke
				(width 0.1)
				(type default)
			)
			(layer "B.Fab")
		)
		(fp_line
			(start -0.4953 1.6002)
			(end 0.4953 1.6002)
			(stroke
				(width 0.1)
				(type default)
			)
			(layer "B.Fab")
		)
		(pad "1" smd rect
			(at 0 0 270)
			(size 0.762 0.889)
			(layers "B.Cu" "B.Mask" "B.Paste")
			(net "P1V5_LAN")
		)
		(pad "2" smd rect
			(at 0 1.397 270)
			(size 0.762 0.889)
			(layers "B.Cu" "B.Mask" "B.Paste")
			(net "P3V3_STBY_P1V5_LAN_I210")
		)
		(zone
			(layer "B.Cu")
			(hatch none 0.5)
			(connect_pads
				(clearance 0)
			)
			(min_thickness 0.25)
			(keepout
				(tracks not_allowed)
				(vias allowed)
				(pads allowed)
				(copperpour not_allowed)
				(footprints allowed)
			)
			(placement
				(enabled no)
				(sheetname "")
			)
			(fill
				(thermal_gap 0.5)
				(thermal_bridge_width 0.5)
				(island_removal_mode 0)
			)
			(polygon
				(pts
					(xy 477.3676 -37.9222) (xy 476.8596 -37.9222) (xy 476.8596 -37.1602) (xy 477.3676 -37.1602)
				)
			)
		)
		(zone
			(layer "B.Cu")
			(hatch none 0.5)
			(connect_pads
				(clearance 0)
			)
			(min_thickness 0.25)
			(keepout
				(tracks allowed)
				(vias not_allowed)
				(pads allowed)
				(copperpour not_allowed)
				(footprints allowed)
			)
			(placement
				(enabled no)
				(sheetname "")
			)
			(fill
				(thermal_gap 0.5)
				(thermal_bridge_width 0.5)
				(island_removal_mode 0)
			)
			(polygon
				(pts
					(xy 477.3676 -37.1602) (xy 476.8596 -37.1602) (xy 476.8596 -37.9222) (xy 477.3676 -37.9222)
				)
			)
		)
	)
	(footprint ""
		(layer "B.Cu")
		(at 340.741 -82.7024 90)
		(property "Reference" "R3P26"
			(at 0 0 90)
			(layer "B.SilkS")
			(hide yes)
			(effects
				(font
					(size 1.27 1.27)
				)
				(justify mirror)
			)
		)
		(property "Value" ""
			(at 0 0 90)
			(layer "B.Fab")
			(effects
				(font
					(size 1.27 1.27)
				)
				(justify mirror)
			)
		)
		(duplicate_pad_numbers_are_jumpers no)
		(fp_poly
			(pts
				(xy 0.2794 -0.1016) (xy -0.2794 -0.1016) (xy -0.2794 0.9906) (xy 0.2794 0.9906)
			)
			(stroke
				(width 0)
				(type default)
			)
			(fill no)
			(layer "B.CrtYd")
		)
		(fp_line
			(start 0.2794 -0.1016)
			(end 0.2794 0.9906)
			(stroke
				(width 0.1)
				(type default)
			)
			(layer "B.Fab")
		)
		(fp_line
			(start -0.2794 -0.1016)
			(end 0.2794 -0.1016)
			(stroke
				(width 0.1)
				(type default)
			)
			(layer "B.Fab")
		)
		(fp_line
			(start 0.2794 0.9906)
			(end -0.2794 0.9906)
			(stroke
				(width 0.1)
				(type default)
			)
			(layer "B.Fab")
		)
		(fp_line
			(start -0.2794 0.9906)
			(end -0.2794 -0.1016)
			(stroke
				(width 0.1)
				(type default)
			)
			(layer "B.Fab")
		)
		(pad "1" smd rect
			(at 0 0 270)
			(size 0.508 0.508)
			(layers "B.Cu" "B.Mask" "B.Paste")
			(net "FM_PVCCIO_CPU0_EN")
		)
		(pad "2" smd rect
			(at 0 0.889 270)
			(size 0.508 0.508)
			(layers "B.Cu" "B.Mask" "B.Paste")
			(net "VR_PVCCIO_CPU0_EN")
		)
		(zone
			(layer "B.Cu")
			(hatch none 0.5)
			(connect_pads
				(clearance 0)
			)
			(min_thickness 0.25)
			(keepout
				(tracks allowed)
				(vias not_allowed)
				(pads allowed)
				(copperpour not_allowed)
				(footprints allowed)
			)
			(placement
				(enabled no)
				(sheetname "")
			)
			(fill
				(thermal_gap 0.5)
				(thermal_bridge_width 0.5)
				(island_removal_mode 0)
			)
			(polygon
				(pts
					(xy 340.995 -82.9564) (xy 340.995 -82.4484) (xy 341.376 -82.4484) (xy 341.376 -82.9564)
				)
			)
		)
		(zone
			(layer "B.Cu")
			(hatch none 0.5)
			(connect_pads
				(clearance 0)
			)
			(min_thickness 0.25)
			(keepout
				(tracks not_allowed)
				(vias allowed)
				(pads allowed)
				(copperpour not_allowed)
				(footprints allowed)
			)
			(placement
				(enabled no)
				(sheetname "")
			)
			(fill
				(thermal_gap 0.5)
				(thermal_bridge_width 0.5)
				(island_removal_mode 0)
			)
			(polygon
				(pts
					(xy 341.376 -82.9564) (xy 341.376 -82.4484) (xy 340.995 -82.4484) (xy 340.995 -82.9564)
				)
			)
		)
	)
	(footprint ""
		(layer "B.Cu")
		(at 374.015 -138.1125)
		(property "Reference" "C3L23"
			(at 0 0 0)
			(layer "B.SilkS")
			(hide yes)
			(effects
				(font
					(size 1.27 1.27)
				)
				(justify mirror)
			)
		)
		(property "Value" ""
			(at 0 0 0)
			(layer "B.Fab")
			(effects
				(font
					(size 1.27 1.27)
				)
				(justify mirror)
			)
		)
		(duplicate_pad_numbers_are_jumpers no)
		(fp_poly
			(pts
				(xy 0.4953 -0.2032) (xy -0.4953 -0.2032) (xy -0.4953 1.6002) (xy 0.4953 1.6002)
			)
			(stroke
				(width 0)
				(type default)
			)
			(fill no)
			(layer "B.CrtYd")
		)
		(fp_line
			(start -0.4953 -0.2032)
			(end -0.4953 1.6002)
			(stroke
				(width 0.1)
				(type default)
			)
			(layer "B.Fab")
		)
		(fp_line
			(start -0.4953 1.6002)
			(end 0.4953 1.6002)
			(stroke
				(width 0.1)
				(type default)
			)
			(layer "B.Fab")
		)
		(fp_line
			(start 0.4953 -0.2032)
			(end -0.4953 -0.2032)
			(stroke
				(width 0.1)
				(type default)
			)
			(layer "B.Fab")
		)
		(fp_line
			(start 0.4953 1.6002)
			(end 0.4953 -0.2032)
			(stroke
				(width 0.1)
				(type default)
			)
			(layer "B.Fab")
		)
		(pad "1" smd rect
			(at 0 0 180)
			(size 0.762 0.889)
			(layers "B.Cu" "B.Mask" "B.Paste")
			(net "PVNN_PCH_STBY")
		)
		(pad "2" smd rect
			(at 0 1.397 180)
			(size 0.762 0.889)
			(layers "B.Cu" "B.Mask" "B.Paste")
			(net "GND")
		)
		(zone
			(layer "B.Cu")
			(hatch none 0.5)
			(connect_pads
				(clearance 0)
			)
			(min_thickness 0.25)
			(keepout
				(tracks not_allowed)
				(vias allowed)
				(pads allowed)
				(copperpour not_allowed)
				(footprints allowed)
			)
			(placement
				(enabled no)
				(sheetname "")
			)
			(fill
				(thermal_gap 0.5)
				(thermal_bridge_width 0.5)
				(island_removal_mode 0)
			)
			(polygon
				(pts
					(xy 374.396 -137.668) (xy 373.634 -137.668) (xy 373.634 -137.16) (xy 374.396 -137.16)
				)
			)
		)
	)
)
